(kicad_pcb
	(version 20260206)
	(generator "pcbnew")
	(generator_version "10.0")
	(general
		(thickness 1.6)
		(legacy_teardrops no)
	)
	(paper "A4")
	(title_block
		(title "01162023_DA0F0TEBIF0_F0T_Expander_BD_F_brd_V02_OCP.brd")
		(comment 1 "Grand Teton / footprint 4451 of 9728 (PEX3), pads 475-594 of 2397")
	)
	(layers
		(0 "F.Cu" signal "TOP")
		(4 "In1.Cu" signal "GND")
		(6 "In2.Cu" signal "VCC")
		(8 "In3.Cu" signal "VCC1")
		(10 "In4.Cu" signal "GND1")
		(12 "In5.Cu" signal "IN1")
		(14 "In6.Cu" signal "GND2")
		(16 "In7.Cu" signal "IN2")
		(18 "In8.Cu" signal "GND3")
		(20 "In9.Cu" signal "IN3")
		(22 "In10.Cu" signal "GND4")
		(24 "In11.Cu" signal "IN4")
		(26 "In12.Cu" signal "GND5")
		(28 "In13.Cu" signal "IN5")
		(30 "In14.Cu" signal "GND6")
		(32 "In15.Cu" signal "IN6")
		(34 "In16.Cu" signal "GND7")
		(2 "B.Cu" signal "BOTTOM")
		(9 "F.Adhes" user "F.Adhesive")
		(11 "B.Adhes" user "B.Adhesive")
		(13 "F.Paste" user "Package Geometry/Pastemask Top")
		(15 "B.Paste" user "Package Geometry/Pastemask Bottom")
		(5 "F.SilkS" user "Ref Des/Silkscreen Top")
		(7 "B.SilkS" user "Ref Des/Silkscreen Bottom")
		(1 "F.Mask" user "Board Geometry/Soldermask Top")
		(3 "B.Mask" user "Board Geometry/Soldermask Bottom")
		(17 "Dwgs.User" user "User.Drawings")
		(19 "Cmts.User" user "User.Comments")
		(21 "Eco1.User" user "User.Eco1")
		(23 "Eco2.User" user "User.Eco2")
		(25 "Edge.Cuts" user "Board Geometry/Outline")
		(27 "Margin" user)
		(31 "F.CrtYd" user "Package Geometry/Place Bound Top")
		(29 "B.CrtYd" user "Package Geometry/Place Bound Bottom")
		(35 "F.Fab" user "Ref Des/Assembly Top")
		(33 "B.Fab" user "Ref Des/Assembly Bottom")
	)
	(footprint ""
		(layer "F.Cu")
		(at 407.949908 -295.89984)
		(property "Reference" "PEX3"
			(at -3.358642 35.5727 0)
			(unlocked yes)
			(layer "F.SilkS")
			(effects
				(font
					(size 2.032 1.524)
					(thickness 0.1524)
				)
				(justify left)
			)
		)
		(property "Value" ""
			(at 0 0 0)
			(layer "F.Fab")
			(effects
				(font
					(size 1.27 1.27)
				)
			)
		)
		(duplicate_pad_numbers_are_jumpers no)
		(pad "AJ36" smd circle
			(at 10.450068 3.800094)
			(size 0.4572 0.4572)
			(layers "F.Cu" "F.Mask" "F.Paste")
			(net "GND")
		)
		(pad "AJ37" smd circle
			(at 11.400028 3.800094)
			(size 0.4572 0.4572)
			(layers "F.Cu" "F.Mask" "F.Paste")
			(net "GND")
		)
		(pad "AJ38" smd circle
			(at 12.349988 3.800094)
			(size 0.4572 0.4572)
			(layers "F.Cu" "F.Mask" "F.Paste")
			(net "UART_PEX3_CLI_TX")
		)
		(pad "AJ39" smd circle
			(at 13.299948 3.800094)
			(size 0.4572 0.4572)
			(layers "F.Cu" "F.Mask" "F.Paste")
			(net "Net_5418")
		)
		(pad "AJ40" smd circle
			(at 14.249908 3.800094)
			(size 0.4572 0.4572)
			(layers "F.Cu" "F.Mask" "F.Paste")
			(net "GND")
		)
		(pad "AJ41" smd circle
			(at 15.200122 3.800094)
			(size 0.4572 0.4572)
			(layers "F.Cu" "F.Mask" "F.Paste")
			(net "GND")
		)
		(pad "AJ42" smd circle
			(at 16.150082 3.800094)
			(size 0.4572 0.4572)
			(layers "F.Cu" "F.Mask" "F.Paste")
			(net "GND")
		)
		(pad "AJ43" smd circle
			(at 17.100042 3.800094)
			(size 0.4572 0.4572)
			(layers "F.Cu" "F.Mask" "F.Paste")
			(net "Net_1516")
		)
		(pad "AJ44" smd circle
			(at 18.050002 3.800094)
			(size 0.4572 0.4572)
			(layers "F.Cu" "F.Mask" "F.Paste")
			(net "Net_1555")
		)
		(pad "AJ45" smd circle
			(at 18.999962 3.800094)
			(size 0.4572 0.4572)
			(layers "F.Cu" "F.Mask" "F.Paste")
			(net "GND")
		)
		(pad "AJ46" smd circle
			(at 19.949922 3.800094)
			(size 0.4572 0.4572)
			(layers "F.Cu" "F.Mask" "F.Paste")
			(net "Net_1509")
		)
		(pad "AJ47" smd circle
			(at 20.899882 3.800094)
			(size 0.4572 0.4572)
			(layers "F.Cu" "F.Mask" "F.Paste")
			(net "Net_1438")
		)
		(pad "AJ48" smd circle
			(at 21.850096 3.800094)
			(size 0.4572 0.4572)
			(layers "F.Cu" "F.Mask" "F.Paste")
			(net "GND")
		)
		(pad "AJ49" smd circle
			(at 22.800056 3.800094)
			(size 0.4572 0.4572)
			(layers "F.Cu" "F.Mask" "F.Paste")
			(net "GND")
		)
		(pad "AK1" smd circle
			(at -22.800056 4.750054)
			(size 0.4572 0.4572)
			(layers "F.Cu" "F.Mask" "F.Paste")
			(net "GND")
		)
		(pad "AK2" smd circle
			(at -21.850096 4.750054)
			(size 0.4572 0.4572)
			(layers "F.Cu" "F.Mask" "F.Paste")
			(net "GND")
		)
		(pad "AK3" smd circle
			(at -20.899882 4.750054)
			(size 0.4572 0.4572)
			(layers "F.Cu" "F.Mask" "F.Paste")
			(net "GND")
		)
		(pad "AK4" smd circle
			(at -19.949922 4.750054)
			(size 0.4572 0.4572)
			(layers "F.Cu" "F.Mask" "F.Paste")
			(net "Net_539")
		)
		(pad "AK5" smd circle
			(at -18.999962 4.750054)
			(size 0.4572 0.4572)
			(layers "F.Cu" "F.Mask" "F.Paste")
			(net "Net_535")
		)
		(pad "AK6" smd circle
			(at -18.050002 4.750054)
			(size 0.4572 0.4572)
			(layers "F.Cu" "F.Mask" "F.Paste")
			(net "GND")
		)
		(pad "AK7" smd circle
			(at -17.100042 4.750054)
			(size 0.4572 0.4572)
			(layers "F.Cu" "F.Mask" "F.Paste")
			(net "Net_5482")
		)
		(pad "AK8" smd circle
			(at -16.150082 4.750054)
			(size 0.4572 0.4572)
			(layers "F.Cu" "F.Mask" "F.Paste")
			(net "GND")
		)
		(pad "AK9" smd circle
			(at -15.200122 4.750054)
			(size 0.4572 0.4572)
			(layers "F.Cu" "F.Mask" "F.Paste")
			(net "GND")
		)
		(pad "AK10" smd circle
			(at -14.249908 4.750054)
			(size 0.4572 0.4572)
			(layers "F.Cu" "F.Mask" "F.Paste")
			(net "P1V8_PEX")
		)
		(pad "AK11" smd circle
			(at -13.299948 4.750054)
			(size 0.4572 0.4572)
			(layers "F.Cu" "F.Mask" "F.Paste")
			(net "GND")
		)
		(pad "AK12" smd circle
			(at -12.349988 4.750054)
			(size 0.4572 0.4572)
			(layers "F.Cu" "F.Mask" "F.Paste")
			(net "P1V8_PEX")
		)
		(pad "AK13" smd circle
			(at -11.400028 4.750054)
			(size 0.4572 0.4572)
			(layers "F.Cu" "F.Mask" "F.Paste")
			(net "GND")
		)
		(pad "AK14" smd circle
			(at -10.450068 4.750054)
			(size 0.4572 0.4572)
			(layers "F.Cu" "F.Mask" "F.Paste")
			(net "P0V8_PEX3")
		)
		(pad "AK15" smd circle
			(at -9.500108 4.750054)
			(size 0.4572 0.4572)
			(layers "F.Cu" "F.Mask" "F.Paste")
			(net "GND")
		)
		(pad "AK16" smd circle
			(at -8.549894 4.750054)
			(size 0.4572 0.4572)
			(layers "F.Cu" "F.Mask" "F.Paste")
			(net "P0V8_SERDES_VDDA_PEX3")
		)
		(pad "AK17" smd circle
			(at -7.599934 4.750054)
			(size 0.4572 0.4572)
			(layers "F.Cu" "F.Mask" "F.Paste")
			(net "P0V8_SERDES_VDDA_PEX3")
		)
		(pad "AK18" smd circle
			(at -6.649974 4.750054)
			(size 0.4572 0.4572)
			(layers "F.Cu" "F.Mask" "F.Paste")
			(net "P0V8_SERDES_VDDA_PEX3")
		)
		(pad "AK19" smd circle
			(at -5.700014 4.750054)
			(size 0.4572 0.4572)
			(layers "F.Cu" "F.Mask" "F.Paste")
			(net "P0V8_SERDES_VDDA_PEX3")
		)
		(pad "AK20" smd circle
			(at -4.750054 4.750054)
			(size 0.4572 0.4572)
			(layers "F.Cu" "F.Mask" "F.Paste")
			(net "P0V8_SERDES_VDDA_PEX3")
		)
		(pad "AK21" smd circle
			(at -3.800094 4.750054)
			(size 0.4572 0.4572)
			(layers "F.Cu" "F.Mask" "F.Paste")
			(net "P0V8_SERDES_VDDA_PEX3")
		)
		(pad "AK22" smd circle
			(at -2.84988 4.750054)
			(size 0.4572 0.4572)
			(layers "F.Cu" "F.Mask" "F.Paste")
			(net "P0V8_SERDES_VDDA_PEX3")
		)
		(pad "AK23" smd circle
			(at -1.89992 4.750054)
			(size 0.4572 0.4572)
			(layers "F.Cu" "F.Mask" "F.Paste")
			(net "P0V8_SERDES_VDDA_PEX3")
		)
		(pad "AK24" smd circle
			(at -0.94996 4.750054)
			(size 0.4572 0.4572)
			(layers "F.Cu" "F.Mask" "F.Paste")
			(net "P0V8_SERDES_VDDA_PEX3")
		)
		(pad "AK25" smd circle
			(at 0 4.750054)
			(size 0.4572 0.4572)
			(layers "F.Cu" "F.Mask" "F.Paste")
			(net "P0V8_SERDES_VDDA_PEX3")
		)
		(pad "AK26" smd circle
			(at 0.94996 4.750054)
			(size 0.4572 0.4572)
			(layers "F.Cu" "F.Mask" "F.Paste")
			(net "P0V8_SERDES_VDDA_PEX3")
		)
		(pad "AK27" smd circle
			(at 1.89992 4.750054)
			(size 0.4572 0.4572)
			(layers "F.Cu" "F.Mask" "F.Paste")
			(net "P0V8_SERDES_VDDA_PEX3")
		)
		(pad "AK28" smd circle
			(at 2.84988 4.750054)
			(size 0.4572 0.4572)
			(layers "F.Cu" "F.Mask" "F.Paste")
			(net "P0V8_SERDES_VDDA_PEX3")
		)
		(pad "AK29" smd circle
			(at 3.800094 4.750054)
			(size 0.4572 0.4572)
			(layers "F.Cu" "F.Mask" "F.Paste")
			(net "P0V8_SERDES_VDDA_PEX3")
		)
		(pad "AK30" smd circle
			(at 4.750054 4.750054)
			(size 0.4572 0.4572)
			(layers "F.Cu" "F.Mask" "F.Paste")
			(net "P0V8_SERDES_VDDA_PEX3")
		)
		(pad "AK31" smd circle
			(at 5.700014 4.750054)
			(size 0.4572 0.4572)
			(layers "F.Cu" "F.Mask" "F.Paste")
			(net "P0V8_SERDES_VDDA_PEX3")
		)
		(pad "AK32" smd circle
			(at 6.649974 4.750054)
			(size 0.4572 0.4572)
			(layers "F.Cu" "F.Mask" "F.Paste")
			(net "P0V8_SERDES_VDDA_PEX3")
		)
		(pad "AK33" smd circle
			(at 7.599934 4.750054)
			(size 0.4572 0.4572)
			(layers "F.Cu" "F.Mask" "F.Paste")
			(net "P0V8_SERDES_VDDA_PEX3")
		)
		(pad "AK34" smd circle
			(at 8.549894 4.750054)
			(size 0.4572 0.4572)
			(layers "F.Cu" "F.Mask" "F.Paste")
			(net "GND")
		)
		(pad "AK35" smd circle
			(at 9.500108 4.750054)
			(size 0.4572 0.4572)
			(layers "F.Cu" "F.Mask" "F.Paste")
			(net "P1V8_PEX")
		)
		(pad "AK36" smd circle
			(at 10.450068 4.750054)
			(size 0.4572 0.4572)
			(layers "F.Cu" "F.Mask" "F.Paste")
			(net "GND")
		)
		(pad "AK37" smd circle
			(at 11.400028 4.750054)
			(size 0.4572 0.4572)
			(layers "F.Cu" "F.Mask" "F.Paste")
			(net "GND")
		)
		(pad "AK38" smd circle
			(at 12.349988 4.750054)
			(size 0.4572 0.4572)
			(layers "F.Cu" "F.Mask" "F.Paste")
			(net "UART_PEX3_CLI_BUF_RX")
		)
		(pad "AK39" smd circle
			(at 13.299948 4.750054)
			(size 0.4572 0.4572)
			(layers "F.Cu" "F.Mask" "F.Paste")
			(net "UART_PEX3_SDB_BUF_RX")
		)
		(pad "AK40" smd circle
			(at 14.249908 4.750054)
			(size 0.4572 0.4572)
			(layers "F.Cu" "F.Mask" "F.Paste")
			(net "GND")
		)
		(pad "AK41" smd circle
			(at 15.200122 4.750054)
			(size 0.4572 0.4572)
			(layers "F.Cu" "F.Mask" "F.Paste")
			(net "Net_1541")
		)
		(pad "AK42" smd circle
			(at 16.150082 4.750054)
			(size 0.4572 0.4572)
			(layers "F.Cu" "F.Mask" "F.Paste")
			(net "Net_1520")
		)
		(pad "AK43" smd circle
			(at 17.100042 4.750054)
			(size 0.4572 0.4572)
			(layers "F.Cu" "F.Mask" "F.Paste")
			(net "GND")
		)
		(pad "AK44" smd circle
			(at 18.050002 4.750054)
			(size 0.4572 0.4572)
			(layers "F.Cu" "F.Mask" "F.Paste")
			(net "GND")
		)
		(pad "AK45" smd circle
			(at 18.999962 4.750054)
			(size 0.4572 0.4572)
			(layers "F.Cu" "F.Mask" "F.Paste")
			(net "GND")
		)
		(pad "AK46" smd circle
			(at 19.949922 4.750054)
			(size 0.4572 0.4572)
			(layers "F.Cu" "F.Mask" "F.Paste")
			(net "GND")
		)
		(pad "AK47" smd circle
			(at 20.899882 4.750054)
			(size 0.4572 0.4572)
			(layers "F.Cu" "F.Mask" "F.Paste")
			(net "GND")
		)
		(pad "AK48" smd circle
			(at 21.850096 4.750054)
			(size 0.4572 0.4572)
			(layers "F.Cu" "F.Mask" "F.Paste")
			(net "Net_1494")
		)
		(pad "AK49" smd circle
			(at 22.800056 4.750054)
			(size 0.4572 0.4572)
			(layers "F.Cu" "F.Mask" "F.Paste")
			(net "Net_1480")
		)
		(pad "AL1" smd circle
			(at -22.800056 5.700014)
			(size 0.4572 0.4572)
			(layers "F.Cu" "F.Mask" "F.Paste")
			(net "GND")
		)
		(pad "AL2" smd circle
			(at -21.850096 5.700014)
			(size 0.4572 0.4572)
			(layers "F.Cu" "F.Mask" "F.Paste")
			(net "GND")
		)
		(pad "AL3" smd circle
			(at -20.899882 5.700014)
			(size 0.4572 0.4572)
			(layers "F.Cu" "F.Mask" "F.Paste")
			(net "GND")
		)
		(pad "AL4" smd circle
			(at -19.949922 5.700014)
			(size 0.4572 0.4572)
			(layers "F.Cu" "F.Mask" "F.Paste")
			(net "GND")
		)
		(pad "AL5" smd circle
			(at -18.999962 5.700014)
			(size 0.4572 0.4572)
			(layers "F.Cu" "F.Mask" "F.Paste")
			(net "GND")
		)
		(pad "AL6" smd circle
			(at -18.050002 5.700014)
			(size 0.4572 0.4572)
			(layers "F.Cu" "F.Mask" "F.Paste")
			(net "GND")
		)
		(pad "AL7" smd circle
			(at -17.100042 5.700014)
			(size 0.4572 0.4572)
			(layers "F.Cu" "F.Mask" "F.Paste")
			(net "GND")
		)
		(pad "AL8" smd circle
			(at -16.150082 5.700014)
			(size 0.4572 0.4572)
			(layers "F.Cu" "F.Mask" "F.Paste")
			(net "GND")
		)
		(pad "AL9" smd circle
			(at -15.200122 5.700014)
			(size 0.4572 0.4572)
			(layers "F.Cu" "F.Mask" "F.Paste")
			(net "GND")
		)
		(pad "AL10" smd circle
			(at -14.249908 5.700014)
			(size 0.4572 0.4572)
			(layers "F.Cu" "F.Mask" "F.Paste")
			(net "GND")
		)
		(pad "AL11" smd circle
			(at -13.299948 5.700014)
			(size 0.4572 0.4572)
			(layers "F.Cu" "F.Mask" "F.Paste")
			(net "GND")
		)
		(pad "AL12" smd circle
			(at -12.349988 5.700014)
			(size 0.4572 0.4572)
			(layers "F.Cu" "F.Mask" "F.Paste")
			(net "GND")
		)
		(pad "AL13" smd circle
			(at -11.400028 5.700014)
			(size 0.4572 0.4572)
			(layers "F.Cu" "F.Mask" "F.Paste")
			(net "GND")
		)
		(pad "AL14" smd circle
			(at -10.450068 5.700014)
			(size 0.4572 0.4572)
			(layers "F.Cu" "F.Mask" "F.Paste")
			(net "VSSA_SENSE")
		)
		(pad "AL15" smd circle
			(at -9.500108 5.700014)
			(size 0.4572 0.4572)
			(layers "F.Cu" "F.Mask" "F.Paste")
			(net "VDDA_SENSE")
		)
		(pad "AL16" smd circle
			(at -8.549894 5.700014)
			(size 0.4572 0.4572)
			(layers "F.Cu" "F.Mask" "F.Paste")
			(net "GND")
		)
		(pad "AL17" smd circle
			(at -7.599934 5.700014)
			(size 0.4572 0.4572)
			(layers "F.Cu" "F.Mask" "F.Paste")
			(net "GND")
		)
		(pad "AL18" smd circle
			(at -6.649974 5.700014)
			(size 0.4572 0.4572)
			(layers "F.Cu" "F.Mask" "F.Paste")
			(net "GND")
		)
		(pad "AL19" smd circle
			(at -5.700014 5.700014)
			(size 0.4572 0.4572)
			(layers "F.Cu" "F.Mask" "F.Paste")
			(net "GND")
		)
		(pad "AL20" smd circle
			(at -4.750054 5.700014)
			(size 0.4572 0.4572)
			(layers "F.Cu" "F.Mask" "F.Paste")
			(net "GND")
		)
		(pad "AL21" smd circle
			(at -3.800094 5.700014)
			(size 0.4572 0.4572)
			(layers "F.Cu" "F.Mask" "F.Paste")
			(net "GND")
		)
		(pad "AL22" smd circle
			(at -2.84988 5.700014)
			(size 0.4572 0.4572)
			(layers "F.Cu" "F.Mask" "F.Paste")
			(net "GND")
		)
		(pad "AL23" smd circle
			(at -1.89992 5.700014)
			(size 0.4572 0.4572)
			(layers "F.Cu" "F.Mask" "F.Paste")
			(net "GND")
		)
		(pad "AL24" smd circle
			(at -0.94996 5.700014)
			(size 0.4572 0.4572)
			(layers "F.Cu" "F.Mask" "F.Paste")
			(net "GND")
		)
		(pad "AL25" smd circle
			(at 0 5.700014)
			(size 0.4572 0.4572)
			(layers "F.Cu" "F.Mask" "F.Paste")
			(net "GND")
		)
		(pad "AL26" smd circle
			(at 0.94996 5.700014)
			(size 0.4572 0.4572)
			(layers "F.Cu" "F.Mask" "F.Paste")
			(net "GND")
		)
		(pad "AL27" smd circle
			(at 1.89992 5.700014)
			(size 0.4572 0.4572)
			(layers "F.Cu" "F.Mask" "F.Paste")
			(net "GND")
		)
		(pad "AL28" smd circle
			(at 2.84988 5.700014)
			(size 0.4572 0.4572)
			(layers "F.Cu" "F.Mask" "F.Paste")
			(net "GND")
		)
		(pad "AL29" smd circle
			(at 3.800094 5.700014)
			(size 0.4572 0.4572)
			(layers "F.Cu" "F.Mask" "F.Paste")
			(net "GND")
		)
		(pad "AL30" smd circle
			(at 4.750054 5.700014)
			(size 0.4572 0.4572)
			(layers "F.Cu" "F.Mask" "F.Paste")
			(net "GND")
		)
		(pad "AL31" smd circle
			(at 5.700014 5.700014)
			(size 0.4572 0.4572)
			(layers "F.Cu" "F.Mask" "F.Paste")
			(net "GND")
		)
		(pad "AL32" smd circle
			(at 6.649974 5.700014)
			(size 0.4572 0.4572)
			(layers "F.Cu" "F.Mask" "F.Paste")
			(net "GND")
		)
		(pad "AL33" smd circle
			(at 7.599934 5.700014)
			(size 0.4572 0.4572)
			(layers "F.Cu" "F.Mask" "F.Paste")
			(net "GND")
		)
		(pad "AL34" smd circle
			(at 8.549894 5.700014)
			(size 0.4572 0.4572)
			(layers "F.Cu" "F.Mask" "F.Paste")
			(net "GND")
		)
		(pad "AL35" smd circle
			(at 9.500108 5.700014)
			(size 0.4572 0.4572)
			(layers "F.Cu" "F.Mask" "F.Paste")
			(net "P1V8_PEX")
		)
		(pad "AL36" smd circle
			(at 10.450068 5.700014)
			(size 0.4572 0.4572)
			(layers "F.Cu" "F.Mask" "F.Paste")
			(net "GND")
		)
		(pad "AL37" smd circle
			(at 11.400028 5.700014)
			(size 0.4572 0.4572)
			(layers "F.Cu" "F.Mask" "F.Paste")
			(net "GND")
		)
		(pad "AL38" smd circle
			(at 12.349988 5.700014)
			(size 0.4572 0.4572)
			(layers "F.Cu" "F.Mask" "F.Paste")
			(net "Net_5449")
		)
		(pad "AL39" smd circle
			(at 13.299948 5.700014)
			(size 0.4572 0.4572)
			(layers "F.Cu" "F.Mask" "F.Paste")
			(net "UART_PEX3_SDB_TX")
		)
		(pad "AL40" smd circle
			(at 14.249908 5.700014)
			(size 0.4572 0.4572)
			(layers "F.Cu" "F.Mask" "F.Paste")
			(net "GND")
		)
		(pad "AL41" smd circle
			(at 15.200122 5.700014)
			(size 0.4572 0.4572)
			(layers "F.Cu" "F.Mask" "F.Paste")
			(net "GND")
		)
		(pad "AL42" smd circle
			(at 16.150082 5.700014)
			(size 0.4572 0.4572)
			(layers "F.Cu" "F.Mask" "F.Paste")
			(net "GND")
		)
		(pad "AL43" smd circle
			(at 17.100042 5.700014)
			(size 0.4572 0.4572)
			(layers "F.Cu" "F.Mask" "F.Paste")
			(net "Net_1525")
		)
		(pad "AL44" smd circle
			(at 18.050002 5.700014)
			(size 0.4572 0.4572)
			(layers "F.Cu" "F.Mask" "F.Paste")
			(net "Net_1517")
		)
		(pad "AL45" smd circle
			(at 18.999962 5.700014)
			(size 0.4572 0.4572)
			(layers "F.Cu" "F.Mask" "F.Paste")
			(net "GND")
		)
		(pad "AL46" smd circle
			(at 19.949922 5.700014)
			(size 0.4572 0.4572)
			(layers "F.Cu" "F.Mask" "F.Paste")
			(net "Net_1444")
		)
		(pad "AL47" smd circle
			(at 20.899882 5.700014)
			(size 0.4572 0.4572)
			(layers "F.Cu" "F.Mask" "F.Paste")
			(net "Net_1504")
		)
		(pad "AL48" smd circle
			(at 21.850096 5.700014)
			(size 0.4572 0.4572)
			(layers "F.Cu" "F.Mask" "F.Paste")
			(net "GND")
		)
		(pad "AL49" smd circle
			(at 22.800056 5.700014)
			(size 0.4572 0.4572)
			(layers "F.Cu" "F.Mask" "F.Paste")
			(net "GND")
		)
		(pad "AM1" smd circle
			(at -22.800056 6.649974)
			(size 0.4572 0.4572)
			(layers "F.Cu" "F.Mask" "F.Paste")
			(net "Net_1413")
		)
		(pad "AM2" smd circle
			(at -21.850096 6.649974)
			(size 0.4572 0.4572)
			(layers "F.Cu" "F.Mask" "F.Paste")
			(net "Net_1443")
		)
		(pad "AM3" smd circle
			(at -20.899882 6.649974)
			(size 0.4572 0.4572)
			(layers "F.Cu" "F.Mask" "F.Paste")
			(net "GND")
		)
		(pad "AM4" smd circle
			(at -19.949922 6.649974)
			(size 0.4572 0.4572)
			(layers "F.Cu" "F.Mask" "F.Paste")
			(net "GND")
		)
		(pad "AM5" smd circle
			(at -18.999962 6.649974)
			(size 0.4572 0.4572)
			(layers "F.Cu" "F.Mask" "F.Paste")
			(net "GND")
		)
		(pad "AM6" smd circle
			(at -18.050002 6.649974)
			(size 0.4572 0.4572)
			(layers "F.Cu" "F.Mask" "F.Paste")
			(net "GND")
		)
		(pad "AM7" smd circle
			(at -17.100042 6.649974)
			(size 0.4572 0.4572)
			(layers "F.Cu" "F.Mask" "F.Paste")
			(net "GND")
		)
		(pad "AM8" smd circle
			(at -16.150082 6.649974)
			(size 0.4572 0.4572)
			(layers "F.Cu" "F.Mask" "F.Paste")
			(net "Net_1471")
		)
	)
)
